FILE_TYPE = MULTI_PHYS_TABLE;

PART 'MOSFET_NCH_DUAL'

{========================================================================================}
:VALUE          | PART_TYPE | MATERIAL | PART_NUMBER    = STANDARD        | LIFECYCLE      | PART_NUMBER   | JEDEC_TYPE             | DESCRIPTION                                | MANUFTR | MANUF_PN       | RD_CMPLS_LVL | CMPLS_LVL | CLASS | DIP_SMD | FP_ECN             | FROM_PJ       | DATA                              | EE_CHECK_LIST | PSL | PREFERENCE | CREATOR | CREATEDAY  | STATUS ;
{========================================================================================}
 'NTZD3154NT1H' | 'SMLF'    | 'IC'     | 'BAM31540000'(!) = 'End of Design' | 'Comp-Approve' | 'BAM31540000' |'SOT563-6'| 'TRANS MOSFET NTZD3154NT1H(20V,540MA),HF'  | 'ONS'   | 'NTZD3154NT1H' | 'EP(V1)'     | 'EP(V1)'  | 'IC'  | ''      | ''                 | 'S1S-MICHAEL' | 'ONS_NTZD3154N.pdf'               | ''            | ''  | ''         | ''      | '20120419' | ''    
 'NTZD3154NT1H' | 'SMLF'    | 'EMPTY'  | 'BAM31540000'(!) = 'End of Design' | 'Comp-Approve' | 'BAM31540000' |'SOT563-6'| 'TRANS MOSFET NTZD3154NT1H(20V,540MA),HF'  | 'ONS'   | 'NTZD3154NT1H' | 'EP(V1)'     | 'EP(V1)'  | 'IC'  | ''      | ''                 | 'S1S-MICHAEL' | 'ONS_NTZD3154N.pdf'               | ''            | ''  | ''         | ''      | '20120419' | ''    
 'NTZD3154NT1G' | 'SMLF'    | 'IC'     | 'BAM31540003'(!) = 'End of Design' | 'Comp-Approve' | 'BAM31540003' |'SOT563-6'| 'TRANS MOSFET NTZD3154NT1G(20V,540MA)'     | 'ONS'   | 'NTZD3154NT1G' | 'EU'         | 'EU'      | 'IC'  | ''      | ''                 | 'T6V-KOOL'    | 'ONS_NTZD3154NT1G.pdf'            | ''            | ''  | ''         | ''      | '20120421' | ''    
 'NTZD3154NT1G' | 'SMLF'    | 'EMPTY'  | 'BAM31540003'(!) = 'End of Design' | 'Comp-Approve' | 'BAM31540003' |'SOT563-6'| 'TRANS MOSFET NTZD3154NT1G(20V,540MA)'     | 'ONS'   | 'NTZD3154NT1G' | 'EU'         | 'EU'      | 'IC'  | ''      | ''                 | 'T6V-KOOL'    | 'ONS_NTZD3154NT1G.pdf'            | ''            | ''  | ''         | ''      | '20120421' | ''    
 'BSS138DW-7-F' | 'SMLF'    | 'IC'     | 'BAM01380032'(!) = ''              | ''             | 'BAM01380032' |'SOT363A'| 'TRANS MOSFET BSS138DW-7-F(50V.200MA)'     | 'DDS'   | 'BSS138DW-7-F' | 'EP(V1)'     | ''        | 'IC'  | ''      | ''                 | 'S2N-JUMP'    | 'BSS138DW-7-F.pdf'                | ''            | ''  | ''         | ''      | '20120425' | ''    
 'BSS138DW-7-F' | 'SMLF'    | 'EMPTY'  | 'BAM01380032'(!) = ''              | ''             | 'BAM01380032' |'SOT363A'| 'TRANS MOSFET BSS138DW-7-F(50V.200MA)'     | 'DDS'   | 'BSS138DW-7-F' | 'EP(V1)'     | ''        | 'IC'  | ''      | ''                 | 'S2N-JUMP'    | 'BSS138DW-7-F.pdf'                | ''            | ''  | ''         | ''      | '20120425' | ''    
 'DMN2400UV-7'  | 'SMLF'    | 'IC'     | 'BAM24000000'(!) = ''              | ''             | 'BAM24000000' |'SOT563-6XA'| 'TRANS MOS DMN2400UV-7(20V,1.33A,0.53W)'   | 'DDS'   | 'DMN2400UV-7'  | 'EP(V1)'     | 'EP(V1)'  | 'IC'  | ''      | ''                 | 'S1N-AI-JU'   | 'DDS_DMN2400UV.pdf'               | ''            | ''  | ''         | ''      | '20121022' | ''    
 'DMN2400UV-7'  | 'SMLF'    | 'EMPTY'  | 'BAM24000000'(!) = ''              | ''             | 'BAM24000000' |'SOT563-6XA'| 'TRANS MOS DMN2400UV-7(20V,1.33A,0.53W)'   | 'DDS'   | 'DMN2400UV-7'  | 'EP(V1)'     | 'EP(V1)'  | 'IC'  | ''      | ''                 | 'S1N-AI-JU'   | 'DDS_DMN2400UV.pdf'               | ''            | ''  | ''         | ''      | '20121022' | ''    
 'NX7002AKS'    | 'SMLF'    | 'IC'     | 'BAM70020069'(!) = 'End of Design' | 'Comp-Approve' | 'BAM70020069' |'SOT363XB'| 'TRANS MOSFET NX7002AKS(60V,170MA,1.06W)'  | 'NXP'   | 'NX7002AKS'    | 'EP(V1)'     | ''        | 'IC'  | ''      | ''                 | 'S1N-AI-JU'   | 'NXP_NX7002AKS.pdf'               | ''            | ''  | ''         | ''      | '20121129' | ''    
 'NX7002AKS'    | 'SMLF'    | 'EMPTY'  | 'BAM70020069'(!) = 'End of Design' | 'Comp-Approve' | 'BAM70020069' |'SOT363XB'| 'TRANS MOSFET NX7002AKS(60V,170MA,1.06W)'  | 'NXP'   | 'NX7002AKS'    | 'EP(V1)'     | ''        | 'IC'  | ''      | ''                 | 'S1N-AI-JU'   | 'NXP_NX7002AKS.pdf'               | ''            | ''  | ''         | ''      | '20121129' | ''    
 'BSS138BKS'    | 'SMLF'    | 'IC'     | 'BAM01380017'(!) = ''              | ''             | 'BAM01380017' |'SOT363XB'| 'TRANS MOSFET BSS138BKS(60V,0.32A,0.445W)' | 'NXP'   | 'BSS138BKS'    | 'EP(V1)'     | ''        | 'IC'  | ''      | ''                 | 'S2B-YU-LIN'  | 'NXP_BSS138BKS.pdf'               | ''            | ''  | ''         | ''      | '20121218' | ''    
 'BSS138BKS'    | 'SMLF'    | 'EMPTY'  | 'BAM01380017'(!) = ''              | ''             | 'BAM01380017' |'SOT363XB'| 'TRANS MOSFET BSS138BKS(60V,0.32A,0.445W)' | 'NXP'   | 'BSS138BKS'    | 'EP(V1)'     | ''        | 'IC'  | ''      | ''                 | 'S2B-YU-LIN'  | 'NXP_BSS138BKS.pdf'               | ''            | ''  | ''         | ''      | '20121218' | ''    
 '2N7002DWKX-7' | 'SMLF'    | 'IC'     | 'BAM70020079'(!) = 'Potential'     | 'End of Life'  | 'BAM70020079' |'SOT363XA_EOL'| 'TR MOS 2N7002DWKX-7(60V115MA,0.2W)SOT363' | 'DDS'   | '2N7002DWKX-7' | 'EP(V1)'     | 'EP(V1)'  | 'IC'  | ''      | ''                 | 'S4LZ-ROGER'  | 'DDS_2N7002DWKX-7.pdf'            | ''            | ''  | ''         | ''      | '20140506' | ''    
 '2N7002DWKX-7' | 'SMLF'    | 'EMPTY'  | 'BAM70020079'(!) = 'Potential'     | 'End of Life'  | 'BAM70020079' |'SOT363XA_EOL'| 'TR MOS 2N7002DWKX-7(60V115MA,0.2W)SOT363' | 'DDS'   | '2N7002DWKX-7' | 'EP(V1)'     | 'EP(V1)'  | 'IC'  | ''      | ''                 | 'S4LZ-ROGER'  | 'DDS_2N7002DWKX-7.pdf'            | ''            | ''  | ''         | ''      | '20140506' | ''    
 'NTJD4001NT1G' | 'SMLF'    | 'IC'     | 'BAM40010011'(!) = 'End of Design' | 'Comp-Approve' | 'BAM40010011' |'SOT363'| 'TRANS MOS NTJD4001NT1G(30V,0.25A)SC-88'   | 'ONS'   | 'NTJD4001NT1G' | 'EU'         | 'EU'      | 'IC'  | ''      | ''                 | 'T2R-GAVEN '  | 'ONS_NTJD4001N.pdf'               | ''            | ''  | ''         | ''      | '20140710' | ''    
 'NTJD4001NT1G' | 'SMLF'    | 'EMPTY'  | 'BAM40010011'(!) = 'End of Design' | 'Comp-Approve' | 'BAM40010011' |'SOT363'| 'TRANS MOS NTJD4001NT1G(30V,0.25A)SC-88'   | 'ONS'   | 'NTJD4001NT1G' | 'EU'         | 'EU'      | 'IC'  | ''      | ''                 | 'T2R-GAVEN '  | 'ONS_NTJD4001N.pdf'               | ''            | ''  | ''         | ''      | '20140710' | ''    
 '2N7002KDW'    | 'SMLF'    | 'IC'     | 'BAM70020047'(!) = ''              | ''             | 'BAM70020047' |'SOT363XD'| 'TRANS MOS 2N7002KDW(60V115MA,0.2W)SOT363' | 'PJT'   | '2N7002KDW'    | 'EP(V1)'     | 'EP(V1)'  | 'IC'  | ''      | ''                 | 'F06-GLEN'    | 'ONS_NTJD4001N.pdf'               | ''            | ''  | ''         | ''      | '20140923' | ''    
 '2N7002KDW'    | 'SMLF'    | 'EMPTY'  | 'BAM70020047'(!) = ''              | ''             | 'BAM70020047' |'SOT363XD'| 'TRANS MOS 2N7002KDW(60V115MA,0.2W)SOT363' | 'PJT'   | '2N7002KDW'    | 'EP(V1)'     | 'EP(V1)'  | 'IC'  | ''      | ''                 | 'F06-GLEN'    | 'ONS_NTJD4001N.pdf'               | ''            | ''  | ''         | ''      | '20140923' | ''    
 'PJT138K'      | 'SMLF'    | 'IC'     | 'BAM138K0003'(!) = ''              | ''             | 'BAM138K0003' |'SOT363XD'| 'TRANS MOSFET PJT138K(50V,0.36A,0.236W)'   | 'PJT'   | 'PJT138K'      | 'EP(V1)'     | 'EP(V1)'  | 'IC'  | ''      | ''                 | 'F09-MARK'    | 'PJT_PJT138K_revJULY-25-2013.pdf' | ''            | ''  | ''         | ''      | '20160617' | ''    
 'PJT138K'      | 'SMLF'    | 'EMPTY'  | 'BAM138K0003'(!) = ''              | ''             | 'BAM138K0003' |'SOT363XD'| 'TRANS MOSFET PJT138K(50V,0.36A,0.236W)'   | 'PJT'   | 'PJT138K'      | 'EP(V1)'     | 'EP(V1)'  | 'IC'  | ''      | ''                 | 'F09-MARK'    | 'PJT_PJT138K_revJULY-25-2013.pdf' | ''            | ''  | ''         | ''      | '20160617' | ''    
 'DMN53D0LDW-7' | 'SMLF'    | 'IC'     | 'BAM53D00003'(!) = ''              | ''             | 'BAM53D00003' |'SOT363_0-65_2X1-25XC'| 'TRANS MOSFET DMN53D0LDW(50V,0.36A,0.31W)' | 'DDS'   | 'DMN53D0LDW-7' | 'EP(V1)'     | 'EP(V1)'  | 'IC'  | ''      | 'DMN53D0LDW-7.msg' | 'F0G-MILLER'  | 'DDS_DMN53D0LDW-7.pdf'            | ''            | ''  | ''         | ''      | '20190717' | ''    
 'DMN53D0LDW-7' | 'SMLF'    | 'EMPTY'  | 'BAM53D00003'(!) = ''              | ''             | 'BAM53D00003' |'SOT363_0-65_2X1-25XC'| 'TRANS MOSFET DMN53D0LDW(50V,0.36A,0.31W)' | 'DDS'   | 'DMN53D0LDW-7' | 'EP(V1)'     | 'EP(V1)'  | 'IC'  | ''      | 'DMN53D0LDW-7.msg' | 'F0G-MILLER'  | 'DDS_DMN53D0LDW-7.pdf'            | ''            | ''  | ''         | ''      | '20190717' | ''    
 'PJT138KA'     | 'SMLF'    | 'IC'     | 'BAM138K0005'(!) = ''              | ''             | 'BAM138K0005' |'SOT363XD'| 'TRANS MOS PJT138KA(50V,0.36A,0.236W)'     | 'PJT'   | 'PJT138KA'     | 'EP(V1)'     | 'EP(V1)'  | 'IC'  | ''      | ''                 | 'S6S-KYLE'    | 'PJT_PJT138KA.pdf'                | ''            | ''  | ''         | ''      | '20210531' | ''    
 'PJT138KA'     | 'SMLF'    | 'EMPTY'  | 'BAM138K0005'(!) = ''              | ''             | 'BAM138K0005' |'SOT363XD'| 'TRANS MOS PJT138KA(50V,0.36A,0.236W)'     | 'PJT'   | 'PJT138KA'     | 'EP(V1)'     | 'EP(V1)'  | 'IC'  | ''      | ''                 | 'S6S-KYLE'    | 'PJT_PJT138KA.pdf'                | ''            | ''  | ''         | ''      | '20210531' | ''    
 'NX6008NBKS'   | 'SMLF'    | 'IC'     | 'BAM60080000'(!) = ''              | ''             | 'BAM60080000' |'SOT363XB'| 'TRANS MOS NX6008NBKS(60V, 0.22A,260W)'    | 'NXE'   | 'NX6008NBKS'   | 'EP(V1)'     | ''        | 'IC'  | ''      | ''                 | 'F0T-IVES'    | 'NXE_NX6008NBKS.pdf'              | ''            | ''  | ''         | ''      | '20210927' | ''    
 'NX6008NBKS'   | 'SMLF'    | 'EMPTY'  | 'BAM60080000'(!) = ''              | ''             | 'BAM60080000' |'SOT363XB'| 'TRANS MOS NX6008NBKS(60V, 0.22A,260W)'    | 'NXE'   | 'NX6008NBKS'   | 'EP(V1)'     | ''        | 'IC'  | ''      | ''                 | 'F0T-IVES'    | 'NXE_NX6008NBKS.pdf'              | ''            | ''  | ''         | ''      | '20210927' | ''    
 'PJT7838'      | 'SMLF'    | 'IC'     | 'BAM78380000'(!) = ''              | ''               | 'BAM78380000' |'SOT363XD'| 'TRANS MOS PJT7838(50V,400MA,350MW)'       | 'PJT'   | 'PJT7838'      | 'EP(V1)'     | 'EP(V1)'  | 'IC'  | ''      | ''                 | 'S3B-BERNIE'  | 'PJT_PJT7838.pdf'                 | ''            | ''  | ''         | ''      | '20221104' | ''    
 'PJT7838'      | 'SMLF'    | 'EMPTY'  | 'BAM78380000'(!) = ''              | ''               | 'BAM78380000' |'SOT363XD'| 'TRANS MOS PJT7838(50V,400MA,350MW)'       | 'PJT'   | 'PJT7838'      | 'EP(V1)'     | 'EP(V1)'  | 'IC'  | ''      | ''                 | 'S3B-BERNIE'  | 'PJT_PJT7838.pdf'                 | ''            | ''  | ''         | ''      | '20221104' | ''    

END_PART

END.

